(kicad_pcb
	(version 20260206)
	(generator "pcbnew")
	(generator_version "10.0")
	(general
		(thickness 1.6)
		(legacy_teardrops no)
	)
	(paper "A4")
	(title_block
		(title "12092022_DA0F0TFB6D0_F0T_FAN_BOARD_MP5048_D_brd_v02_OCP.brd")
		(comment 1 "Grand Teton / footprints 591-596 of 924")
	)
	(layers
		(0 "F.Cu" signal "TOP")
		(4 "In1.Cu" signal "GND")
		(6 "In2.Cu" signal "IN1")
		(8 "In3.Cu" signal "IN2")
		(10 "In4.Cu" signal "GND1")
		(2 "B.Cu" signal "BOTTOM")
		(9 "F.Adhes" user "F.Adhesive")
		(11 "B.Adhes" user "B.Adhesive")
		(13 "F.Paste" user "Package Geometry/Pastemask Top")
		(15 "B.Paste" user "Package Geometry/Pastemask Bottom")
		(5 "F.SilkS" user "Ref Des/Silkscreen Top")
		(7 "B.SilkS" user "Ref Des/Silkscreen Bottom")
		(1 "F.Mask" user "Board Geometry/Soldermask Top")
		(3 "B.Mask" user "Board Geometry/Soldermask Bottom")
		(17 "Dwgs.User" user "User.Drawings")
		(19 "Cmts.User" user "User.Comments")
		(21 "Eco1.User" user "User.Eco1")
		(23 "Eco2.User" user "User.Eco2")
		(25 "Edge.Cuts" user "Board Geometry/Outline")
		(27 "Margin" user)
		(31 "F.CrtYd" user "Package Geometry/Place Bound Top")
		(29 "B.CrtYd" user "Package Geometry/Place Bound Bottom")
		(35 "F.Fab" user "Ref Des/Assembly Top")
		(33 "B.Fab" user "Ref Des/Assembly Bottom")
	)
	(footprint ""
		(layer "F.Cu")
		(at 3.81 -129.794)
		(property "Reference" "R5566"
			(at 0 0 0)
			(layer "F.SilkS")
			(hide yes)
			(effects
				(font
					(size 1.27 1.27)
				)
			)
		)
		(property "Value" ""
			(at 0 0 0)
			(layer "F.Fab")
			(effects
				(font
					(size 1.27 1.27)
				)
			)
		)
		(duplicate_pad_numbers_are_jumpers no)
		(fp_line
			(start -0.7874 -0.4064)
			(end 0.7874 -0.4064)
			(stroke
				(width 0.1524)
				(type default)
			)
			(layer "F.SilkS")
		)
		(fp_line
			(start -0.7874 0.4064)
			(end -0.7874 -0.4064)
			(stroke
				(width 0.1524)
				(type default)
			)
			(layer "F.SilkS")
		)
		(fp_line
			(start 0.7874 -0.4064)
			(end 0.7874 0.4064)
			(stroke
				(width 0.1524)
				(type default)
			)
			(layer "F.SilkS")
		)
		(fp_line
			(start 0.7874 0.4064)
			(end -0.7874 0.4064)
			(stroke
				(width 0.1524)
				(type default)
			)
			(layer "F.SilkS")
		)
		(fp_line
			(start -0.67945 -0.305054)
			(end -0.12065 -0.305054)
			(stroke
				(width 0.1)
				(type default)
			)
			(layer "F.Fab")
		)
		(fp_line
			(start -0.67945 0.3048)
			(end -0.67945 -0.305054)
			(stroke
				(width 0.1)
				(type default)
			)
			(layer "F.Fab")
		)
		(fp_line
			(start -0.12065 -0.305054)
			(end -0.12065 -0.2794)
			(stroke
				(width 0.1)
				(type default)
			)
			(layer "F.Fab")
		)
		(fp_line
			(start -0.12065 -0.2794)
			(end 0.12065 -0.2794)
			(stroke
				(width 0.1)
				(type default)
			)
			(layer "F.Fab")
		)
		(fp_line
			(start -0.12065 0.2794)
			(end -0.12065 0.3048)
			(stroke
				(width 0.1)
				(type default)
			)
			(layer "F.Fab")
		)
		(fp_line
			(start -0.12065 0.3048)
			(end -0.67945 0.3048)
			(stroke
				(width 0.1)
				(type default)
			)
			(layer "F.Fab")
		)
		(fp_line
			(start 0.120396 0.2794)
			(end -0.12065 0.2794)
			(stroke
				(width 0.1)
				(type default)
			)
			(layer "F.Fab")
		)
		(fp_line
			(start 0.120396 0.3048)
			(end 0.120396 0.2794)
			(stroke
				(width 0.1)
				(type default)
			)
			(layer "F.Fab")
		)
		(fp_line
			(start 0.12065 -0.3048)
			(end 0.67945 -0.3048)
			(stroke
				(width 0.1)
				(type default)
			)
			(layer "F.Fab")
		)
		(fp_line
			(start 0.12065 -0.2794)
			(end 0.12065 -0.3048)
			(stroke
				(width 0.1)
				(type default)
			)
			(layer "F.Fab")
		)
		(fp_line
			(start 0.67945 -0.3048)
			(end 0.67945 0.3048)
			(stroke
				(width 0.1)
				(type default)
			)
			(layer "F.Fab")
		)
		(fp_line
			(start 0.67945 0.3048)
			(end 0.120396 0.3048)
			(stroke
				(width 0.1)
				(type default)
			)
			(layer "F.Fab")
		)
		(pad "1" smd circle
			(at -0.40005 0)
			(size 0 0)
			(layers "F.Cu" "F.Mask" "F.Paste")
			(net "P3V3_AUX")
		)
		(pad "2" smd circle
			(at 0.40005 0)
			(size 0 0)
			(layers "F.Cu" "F.Mask" "F.Paste")
			(net "U404_ADD1")
		)
	)
	(footprint ""
		(layer "F.Cu")
		(at 23.622 -136.017 -90)
		(property "Reference" "R4952"
			(at 0 0 270)
			(layer "F.SilkS")
			(hide yes)
			(effects
				(font
					(size 1.27 1.27)
				)
			)
		)
		(property "Value" ""
			(at 0 0 270)
			(layer "F.Fab")
			(effects
				(font
					(size 1.27 1.27)
				)
			)
		)
		(duplicate_pad_numbers_are_jumpers no)
		(fp_line
			(start -0.7874 0.4064)
			(end -0.7874 -0.4064)
			(stroke
				(width 0.1524)
				(type default)
			)
			(layer "F.SilkS")
		)
		(fp_line
			(start 0.7874 0.4064)
			(end -0.7874 0.4064)
			(stroke
				(width 0.1524)
				(type default)
			)
			(layer "F.SilkS")
		)
		(fp_line
			(start -0.7874 -0.4064)
			(end 0.7874 -0.4064)
			(stroke
				(width 0.1524)
				(type default)
			)
			(layer "F.SilkS")
		)
		(fp_line
			(start 0.7874 -0.4064)
			(end 0.7874 0.4064)
			(stroke
				(width 0.1524)
				(type default)
			)
			(layer "F.SilkS")
		)
		(fp_line
			(start -0.67945 0.3048)
			(end -0.67945 -0.305054)
			(stroke
				(width 0.1)
				(type default)
			)
			(layer "F.Fab")
		)
		(fp_line
			(start -0.12065 0.3048)
			(end -0.67945 0.3048)
			(stroke
				(width 0.1)
				(type default)
			)
			(layer "F.Fab")
		)
		(fp_line
			(start 0.120396 0.3048)
			(end 0.120396 0.2794)
			(stroke
				(width 0.1)
				(type default)
			)
			(layer "F.Fab")
		)
		(fp_line
			(start 0.67945 0.3048)
			(end 0.120396 0.3048)
			(stroke
				(width 0.1)
				(type default)
			)
			(layer "F.Fab")
		)
		(fp_line
			(start -0.12065 0.2794)
			(end -0.12065 0.3048)
			(stroke
				(width 0.1)
				(type default)
			)
			(layer "F.Fab")
		)
		(fp_line
			(start 0.120396 0.2794)
			(end -0.12065 0.2794)
			(stroke
				(width 0.1)
				(type default)
			)
			(layer "F.Fab")
		)
		(fp_line
			(start -0.12065 -0.2794)
			(end 0.12065 -0.2794)
			(stroke
				(width 0.1)
				(type default)
			)
			(layer "F.Fab")
		)
		(fp_line
			(start 0.12065 -0.2794)
			(end 0.12065 -0.3048)
			(stroke
				(width 0.1)
				(type default)
			)
			(layer "F.Fab")
		)
		(fp_line
			(start 0.12065 -0.3048)
			(end 0.67945 -0.3048)
			(stroke
				(width 0.1)
				(type default)
			)
			(layer "F.Fab")
		)
		(fp_line
			(start 0.67945 -0.3048)
			(end 0.67945 0.3048)
			(stroke
				(width 0.1)
				(type default)
			)
			(layer "F.Fab")
		)
		(fp_line
			(start -0.67945 -0.305054)
			(end -0.12065 -0.305054)
			(stroke
				(width 0.1)
				(type default)
			)
			(layer "F.Fab")
		)
		(fp_line
			(start -0.12065 -0.305054)
			(end -0.12065 -0.2794)
			(stroke
				(width 0.1)
				(type default)
			)
			(layer "F.Fab")
		)
		(pad "1" smd circle
			(at -0.40005 0 270)
			(size 0 0)
			(layers "F.Cu" "F.Mask" "F.Paste")
			(net "GND")
		)
		(pad "2" smd circle
			(at 0.40005 0 270)
			(size 0 0)
			(layers "F.Cu" "F.Mask" "F.Paste")
			(net "MAX31790_U330_FREQ_START")
		)
	)
	(footprint ""
		(layer "F.Cu")
		(at 14.0589 -134.874 180)
		(property "Reference" "R5595"
			(at 0 0 180)
			(layer "F.SilkS")
			(hide yes)
			(effects
				(font
					(size 1.27 1.27)
				)
			)
		)
		(property "Value" ""
			(at 0 0 180)
			(layer "F.Fab")
			(effects
				(font
					(size 1.27 1.27)
				)
			)
		)
		(duplicate_pad_numbers_are_jumpers no)
		(fp_line
			(start 0.7874 0.4064)
			(end -0.7874 0.4064)
			(stroke
				(width 0.1524)
				(type default)
			)
			(layer "F.SilkS")
		)
		(fp_line
			(start 0.7874 -0.4064)
			(end 0.7874 0.4064)
			(stroke
				(width 0.1524)
				(type default)
			)
			(layer "F.SilkS")
		)
		(fp_line
			(start -0.7874 0.4064)
			(end -0.7874 -0.4064)
			(stroke
				(width 0.1524)
				(type default)
			)
			(layer "F.SilkS")
		)
		(fp_line
			(start -0.7874 -0.4064)
			(end 0.7874 -0.4064)
			(stroke
				(width 0.1524)
				(type default)
			)
			(layer "F.SilkS")
		)
		(fp_line
			(start 0.67945 0.3048)
			(end 0.120396 0.3048)
			(stroke
				(width 0.1)
				(type default)
			)
			(layer "F.Fab")
		)
		(fp_line
			(start 0.67945 -0.3048)
			(end 0.67945 0.3048)
			(stroke
				(width 0.1)
				(type default)
			)
			(layer "F.Fab")
		)
		(fp_line
			(start 0.12065 -0.2794)
			(end 0.12065 -0.3048)
			(stroke
				(width 0.1)
				(type default)
			)
			(layer "F.Fab")
		)
		(fp_line
			(start 0.12065 -0.3048)
			(end 0.67945 -0.3048)
			(stroke
				(width 0.1)
				(type default)
			)
			(layer "F.Fab")
		)
		(fp_line
			(start 0.120396 0.3048)
			(end 0.120396 0.2794)
			(stroke
				(width 0.1)
				(type default)
			)
			(layer "F.Fab")
		)
		(fp_line
			(start 0.120396 0.2794)
			(end -0.12065 0.2794)
			(stroke
				(width 0.1)
				(type default)
			)
			(layer "F.Fab")
		)
		(fp_line
			(start -0.12065 0.3048)
			(end -0.67945 0.3048)
			(stroke
				(width 0.1)
				(type default)
			)
			(layer "F.Fab")
		)
		(fp_line
			(start -0.12065 0.2794)
			(end -0.12065 0.3048)
			(stroke
				(width 0.1)
				(type default)
			)
			(layer "F.Fab")
		)
		(fp_line
			(start -0.12065 -0.2794)
			(end 0.12065 -0.2794)
			(stroke
				(width 0.1)
				(type default)
			)
			(layer "F.Fab")
		)
		(fp_line
			(start -0.12065 -0.305054)
			(end -0.12065 -0.2794)
			(stroke
				(width 0.1)
				(type default)
			)
			(layer "F.Fab")
		)
		(fp_line
			(start -0.67945 0.3048)
			(end -0.67945 -0.305054)
			(stroke
				(width 0.1)
				(type default)
			)
			(layer "F.Fab")
		)
		(fp_line
			(start -0.67945 -0.305054)
			(end -0.12065 -0.305054)
			(stroke
				(width 0.1)
				(type default)
			)
			(layer "F.Fab")
		)
		(pad "1" smd rect
			(at -0.40005 0)
			(size 0.4572 0.508)
			(layers "F.Cu" "F.Mask" "F.Paste")
			(net "FAN_7_PWM")
		)
		(pad "2" smd rect
			(at 0.40005 0)
			(size 0.4572 0.508)
			(layers "F.Cu" "F.Mask" "F.Paste")
			(net "FAN_7_PWM_R2")
		)
	)
	(footprint ""
		(layer "F.Cu")
		(at 15.377922 -211.776056 180)
		(property "Reference" "D253"
			(at 4.328922 0.414274 0)
			(unlocked yes)
			(layer "F.SilkS")
			(effects
				(font
					(size 0.7874 0.5842)
					(thickness 0.1524)
				)
				(justify left)
			)
		)
		(property "Value" ""
			(at 0 0 180)
			(layer "F.Fab")
			(effects
				(font
					(size 1.27 1.27)
				)
			)
		)
		(duplicate_pad_numbers_are_jumpers no)
		(fp_line
			(start 0.94488 0.450088)
			(end 0.94488 -0.450088)
			(stroke
				(width 0.1524)
				(type default)
			)
			(layer "F.SilkS")
		)
		(fp_line
			(start 0.94488 -0.450088)
			(end -0.854964 -0.450088)
			(stroke
				(width 0.1524)
				(type default)
			)
			(layer "F.SilkS")
		)
		(fp_line
			(start 0.870458 -0.2794)
			(end 0.845058 0.4064)
			(stroke
				(width 0.1524)
				(type default)
			)
			(layer "F.SilkS")
		)
		(fp_line
			(start 0.845058 0.4064)
			(end 0.845058 -0.381)
			(stroke
				(width 0.1524)
				(type default)
			)
			(layer "F.SilkS")
		)
		(fp_line
			(start -0.854964 0.450088)
			(end 0.925068 0.450088)
			(stroke
				(width 0.1524)
				(type default)
			)
			(layer "F.SilkS")
		)
		(fp_line
			(start -0.854964 -0.450088)
			(end -0.854964 0.450088)
			(stroke
				(width 0.1524)
				(type default)
			)
			(layer "F.SilkS")
		)
		(fp_line
			(start 0.54991 0.350012)
			(end 0.54991 -0.350012)
			(stroke
				(width 0.1)
				(type default)
			)
			(layer "F.Fab")
		)
		(fp_line
			(start 0.54991 -0.350012)
			(end -0.54991 -0.350012)
			(stroke
				(width 0.1)
				(type default)
			)
			(layer "F.Fab")
		)
		(fp_line
			(start -0.54991 0.350012)
			(end 0.54991 0.350012)
			(stroke
				(width 0.1)
				(type default)
			)
			(layer "F.Fab")
		)
		(fp_line
			(start -0.54991 -0.350012)
			(end -0.54991 0.350012)
			(stroke
				(width 0.1)
				(type default)
			)
			(layer "F.Fab")
		)
		(fp_text user "-"
			(at 1.280922 1.425194 0)
			(unlocked yes)
			(layer "F.SilkS")
			(effects
				(font
					(size 1.905 1.4224)
					(thickness 0.1524)
				)
				(justify left)
			)
		)
		(fp_text user "+"
			(at 0.264922 1.425194 0)
			(unlocked yes)
			(layer "F.SilkS")
			(effects
				(font
					(size 1.905 1.4224)
					(thickness 0.1524)
				)
				(justify left)
			)
		)
		(fp_text user "-"
			(at 2.48539 0.239014 0)
			(unlocked yes)
			(layer "F.Fab")
			(effects
				(font
					(size 1.905 1.4224)
					(thickness 0.1524)
				)
				(justify left)
			)
		)
		(fp_text user "+"
			(at -0.808228 0.239014 0)
			(unlocked yes)
			(layer "F.Fab")
			(effects
				(font
					(size 1.905 1.4224)
					(thickness 0.1524)
				)
				(justify left)
			)
		)
		(pad "A" smd rect
			(at -0.424942 0 180)
			(size 0.5588 0.6096)
			(layers "F.Cu" "F.Mask" "F.Paste")
			(net "GND")
		)
		(pad "C" smd rect
			(at 0.424942 0)
			(size 0.5588 0.6096)
			(layers "F.Cu" "F.Mask" "F.Paste")
			(net "FAN_6_TACH_OL_D")
		)
	)
	(footprint ""
		(layer "F.Cu")
		(at 32.258 -202.057 90)
		(property "Reference" "R5389"
			(at 0 0 90)
			(layer "F.SilkS")
			(hide yes)
			(effects
				(font
					(size 1.27 1.27)
				)
			)
		)
		(property "Value" ""
			(at 0 0 90)
			(layer "F.Fab")
			(effects
				(font
					(size 1.27 1.27)
				)
			)
		)
		(duplicate_pad_numbers_are_jumpers no)
		(fp_line
			(start 0.7874 -0.4064)
			(end 0.7874 0.4064)
			(stroke
				(width 0.1524)
				(type default)
			)
			(layer "F.SilkS")
		)
		(fp_line
			(start -0.7874 -0.4064)
			(end 0.7874 -0.4064)
			(stroke
				(width 0.1524)
				(type default)
			)
			(layer "F.SilkS")
		)
		(fp_line
			(start 0.7874 0.4064)
			(end -0.7874 0.4064)
			(stroke
				(width 0.1524)
				(type default)
			)
			(layer "F.SilkS")
		)
		(fp_line
			(start -0.7874 0.4064)
			(end -0.7874 -0.4064)
			(stroke
				(width 0.1524)
				(type default)
			)
			(layer "F.SilkS")
		)
		(fp_line
			(start -0.12065 -0.305054)
			(end -0.12065 -0.2794)
			(stroke
				(width 0.1)
				(type default)
			)
			(layer "F.Fab")
		)
		(fp_line
			(start -0.67945 -0.305054)
			(end -0.12065 -0.305054)
			(stroke
				(width 0.1)
				(type default)
			)
			(layer "F.Fab")
		)
		(fp_line
			(start 0.67945 -0.3048)
			(end 0.67945 0.3048)
			(stroke
				(width 0.1)
				(type default)
			)
			(layer "F.Fab")
		)
		(fp_line
			(start 0.12065 -0.3048)
			(end 0.67945 -0.3048)
			(stroke
				(width 0.1)
				(type default)
			)
			(layer "F.Fab")
		)
		(fp_line
			(start 0.12065 -0.2794)
			(end 0.12065 -0.3048)
			(stroke
				(width 0.1)
				(type default)
			)
			(layer "F.Fab")
		)
		(fp_line
			(start -0.12065 -0.2794)
			(end 0.12065 -0.2794)
			(stroke
				(width 0.1)
				(type default)
			)
			(layer "F.Fab")
		)
		(fp_line
			(start 0.120396 0.2794)
			(end -0.12065 0.2794)
			(stroke
				(width 0.1)
				(type default)
			)
			(layer "F.Fab")
		)
		(fp_line
			(start -0.12065 0.2794)
			(end -0.12065 0.3048)
			(stroke
				(width 0.1)
				(type default)
			)
			(layer "F.Fab")
		)
		(fp_line
			(start 0.67945 0.3048)
			(end 0.120396 0.3048)
			(stroke
				(width 0.1)
				(type default)
			)
			(layer "F.Fab")
		)
		(fp_line
			(start 0.120396 0.3048)
			(end 0.120396 0.2794)
			(stroke
				(width 0.1)
				(type default)
			)
			(layer "F.Fab")
		)
		(fp_line
			(start -0.12065 0.3048)
			(end -0.67945 0.3048)
			(stroke
				(width 0.1)
				(type default)
			)
			(layer "F.Fab")
		)
		(fp_line
			(start -0.67945 0.3048)
			(end -0.67945 -0.305054)
			(stroke
				(width 0.1)
				(type default)
			)
			(layer "F.Fab")
		)
		(pad "1" smd circle
			(at -0.40005 0 90)
			(size 0 0)
			(layers "F.Cu" "F.Mask" "F.Paste")
			(net "P3V3_AUX")
		)
		(pad "2" smd circle
			(at 0.40005 0 90)
			(size 0 0)
			(layers "F.Cu" "F.Mask" "F.Paste")
			(net "FAN_1_FAIL_R_LED")
		)
	)
	(footprint ""
		(layer "F.Cu")
		(at 40.4876 -224.3836)
		(property "Reference" "PC23"
			(at -5.334 5.99567 0)
			(unlocked yes)
			(layer "F.SilkS")
			(effects
				(font
					(size 0.7874 0.5842)
					(thickness 0.1524)
				)
				(justify left)
			)
		)
		(property "Value" ""
			(at 0 0 0)
			(layer "F.Fab")
			(effects
				(font
					(size 1.27 1.27)
				)
			)
		)
		(duplicate_pad_numbers_are_jumpers no)
		(fp_line
			(start -5.249926 -3.979926)
			(end -5.249926 -1.2446)
			(stroke
				(width 0.1524)
				(type default)
			)
			(layer "F.SilkS")
		)
		(fp_line
			(start -5.249926 1.2446)
			(end -5.249926 3.979926)
			(stroke
				(width 0.1524)
				(type default)
			)
			(layer "F.SilkS")
		)
		(fp_line
			(start -5.249926 3.979926)
			(end -3.979926 5.249926)
			(stroke
				(width 0.1524)
				(type default)
			)
			(layer "F.SilkS")
		)
		(fp_line
			(start -3.979926 -5.249926)
			(end -5.249926 -3.979926)
			(stroke
				(width 0.1524)
				(type default)
			)
			(layer "F.SilkS")
		)
		(fp_line
			(start -3.979926 5.249926)
			(end 5.249926 5.249926)
			(stroke
				(width 0.1524)
				(type default)
			)
			(layer "F.SilkS")
		)
		(fp_line
			(start 5.249926 -5.249926)
			(end -3.979926 -5.249926)
			(stroke
				(width 0.1524)
				(type default)
			)
			(layer "F.SilkS")
		)
		(fp_line
			(start 5.249926 -1.2446)
			(end 5.249926 -5.249926)
			(stroke
				(width 0.1524)
				(type default)
			)
			(layer "F.SilkS")
		)
		(fp_line
			(start 5.249926 5.249926)
			(end 5.249926 1.2446)
			(stroke
				(width 0.1524)
				(type default)
			)
			(layer "F.SilkS")
		)
		(fp_line
			(start -5.249926 -5.249926)
			(end -5.249926 5.249926)
			(stroke
				(width 0.1)
				(type default)
			)
			(layer "F.Fab")
		)
		(fp_line
			(start -5.249926 5.249926)
			(end 5.249926 5.249926)
			(stroke
				(width 0.1)
				(type default)
			)
			(layer "F.Fab")
		)
		(fp_line
			(start 5.249926 -5.249926)
			(end -5.249926 -5.249926)
			(stroke
				(width 0.1)
				(type default)
			)
			(layer "F.Fab")
		)
		(fp_line
			(start 5.249926 5.249926)
			(end 5.249926 -5.249926)
			(stroke
				(width 0.1)
				(type default)
			)
			(layer "F.Fab")
		)
		(pad "1" smd rect
			(at -4.45008 0 90)
			(size 2.2098 4.4196)
			(layers "F.Cu" "F.Mask" "F.Paste")
			(net "P52V_FAN_1")
		)
		(pad "2" smd rect
			(at 4.45008 0 90)
			(size 2.2098 4.4196)
			(layers "F.Cu" "F.Mask" "F.Paste")
			(net "GND")
		)
	)
)
